# S9S_MB_2U (Grand Teton) — schematic netlist excerpt (pin names and nets, part order shuffled) for the footprints in the layout excerpt that follows; sources: Cadence DE-HDL packaged netlist, KiCad conversion of 03242023_DA0F0TMBIJ0_F0T_Motherboard_J_brd_V01_OCP.brd

C1336  Q_CAP  10UF 6.3V 20% X6S  pkg C0402  page 296 : A = PVNN_TERM_CPU1 ; B = GND
PR133  Q_RES  8.87K 1% EMPTY  pkg 0402LF  page 270 : A = PVCCIN_CPU0_LSET7 ; B = GND

(kicad_pcb
	(version 20260206)
	(generator "pcbnew")
	(generator_version "10.0")
	(general
		(thickness 1.6)
		(legacy_teardrops no)
	)
	(paper "A4")
	(title_block
		(title "03242023_DA0F0TMBIJ0_F0T_Motherboard_J_brd_V01_OCP.brd")
		(comment 1 "Grand Teton / footprints 670-671 of 6105")
	)
	(layers
		(0 "F.Cu" signal "TOP")
		(4 "In1.Cu" signal "GND")
		(6 "In2.Cu" signal "IN1")
		(8 "In3.Cu" signal "GND1")
		(10 "In4.Cu" signal "IN2")
		(12 "In5.Cu" signal "GND2")
		(14 "In6.Cu" signal "IN3")
		(16 "In7.Cu" signal "GND3")
		(18 "In8.Cu" signal "VCC")
		(20 "In9.Cu" signal "VCC1")
		(22 "In10.Cu" signal "GND4")
		(24 "In11.Cu" signal "IN4")
		(26 "In12.Cu" signal "GND5")
		(28 "In13.Cu" signal "IN5")
		(30 "In14.Cu" signal "GND6")
		(32 "In15.Cu" signal "IN6")
		(34 "In16.Cu" signal "GND7")
		(2 "B.Cu" signal "BOTTOM")
		(9 "F.Adhes" user "F.Adhesive")
		(11 "B.Adhes" user "B.Adhesive")
		(13 "F.Paste" user "Package Geometry/Pastemask Top")
		(15 "B.Paste" user "Package Geometry/Pastemask Bottom")
		(5 "F.SilkS" user "Ref Des/Silkscreen Top")
		(7 "B.SilkS" user "Ref Des/Silkscreen Bottom")
		(1 "F.Mask" user "Board Geometry/Soldermask Top")
		(3 "B.Mask" user "Board Geometry/Soldermask Bottom")
		(17 "Dwgs.User" user "User.Drawings")
		(19 "Cmts.User" user "User.Comments")
		(21 "Eco1.User" user "User.Eco1")
		(23 "Eco2.User" user "User.Eco2")
		(25 "Edge.Cuts" user "Board Geometry/Outline")
		(27 "Margin" user)
		(31 "F.CrtYd" user "Package Geometry/Place Bound Top")
		(29 "B.CrtYd" user "Package Geometry/Place Bound Bottom")
		(35 "F.Fab" user "Ref Des/Assembly Top")
		(33 "B.Fab" user "Ref Des/Assembly Bottom")
	)
	(footprint ""
		(layer "F.Cu")
		(at 327.636378 -347.990922)
		(property "Reference" "PR133"
			(at 0 0 0)
			(layer "F.SilkS")
			(hide yes)
			(effects
				(font
					(size 1.27 1.27)
				)
			)
		)
		(property "Value" ""
			(at 0 0 0)
			(layer "F.Fab")
			(effects
				(font
					(size 1.27 1.27)
				)
			)
		)
		(duplicate_pad_numbers_are_jumpers no)
		(fp_line
			(start -0.7874 -0.4064)
			(end 0.7874 -0.4064)
			(stroke
				(width 0.1524)
				(type default)
			)
			(layer "F.SilkS")
		)
		(fp_line
			(start -0.7874 0.4064)
			(end -0.7874 -0.4064)
			(stroke
				(width 0.1524)
				(type default)
			)
			(layer "F.SilkS")
		)
		(fp_line
			(start 0.7874 -0.4064)
			(end 0.7874 0.4064)
			(stroke
				(width 0.1524)
				(type default)
			)
			(layer "F.SilkS")
		)
		(fp_line
			(start 0.7874 0.4064)
			(end -0.7874 0.4064)
			(stroke
				(width 0.1524)
				(type default)
			)
			(layer "F.SilkS")
		)
		(fp_line
			(start -0.67945 -0.305054)
			(end -0.12065 -0.305054)
			(stroke
				(width 0.1)
				(type default)
			)
			(layer "F.Fab")
		)
		(fp_line
			(start -0.67945 0.3048)
			(end -0.67945 -0.305054)
			(stroke
				(width 0.1)
				(type default)
			)
			(layer "F.Fab")
		)
		(fp_line
			(start -0.12065 -0.305054)
			(end -0.12065 -0.2794)
			(stroke
				(width 0.1)
				(type default)
			)
			(layer "F.Fab")
		)
		(fp_line
			(start -0.12065 -0.2794)
			(end 0.12065 -0.2794)
			(stroke
				(width 0.1)
				(type default)
			)
			(layer "F.Fab")
		)
		(fp_line
			(start -0.12065 0.2794)
			(end -0.12065 0.3048)
			(stroke
				(width 0.1)
				(type default)
			)
			(layer "F.Fab")
		)
		(fp_line
			(start -0.12065 0.3048)
			(end -0.67945 0.3048)
			(stroke
				(width 0.1)
				(type default)
			)
			(layer "F.Fab")
		)
		(fp_line
			(start 0.120396 0.2794)
			(end -0.12065 0.2794)
			(stroke
				(width 0.1)
				(type default)
			)
			(layer "F.Fab")
		)
		(fp_line
			(start 0.120396 0.3048)
			(end 0.120396 0.2794)
			(stroke
				(width 0.1)
				(type default)
			)
			(layer "F.Fab")
		)
		(fp_line
			(start 0.12065 -0.3048)
			(end 0.67945 -0.3048)
			(stroke
				(width 0.1)
				(type default)
			)
			(layer "F.Fab")
		)
		(fp_line
			(start 0.12065 -0.2794)
			(end 0.12065 -0.3048)
			(stroke
				(width 0.1)
				(type default)
			)
			(layer "F.Fab")
		)
		(fp_line
			(start 0.67945 -0.3048)
			(end 0.67945 0.3048)
			(stroke
				(width 0.1)
				(type default)
			)
			(layer "F.Fab")
		)
		(fp_line
			(start 0.67945 0.3048)
			(end 0.120396 0.3048)
			(stroke
				(width 0.1)
				(type default)
			)
			(layer "F.Fab")
		)
		(pad "1" smd circle
			(at -0.40005 0)
			(size 0 0)
			(layers "F.Cu" "F.Mask" "F.Paste")
			(net "PVCCIN_CPU0_LSET7")
		)
		(pad "2" smd circle
			(at 0.40005 0)
			(size 0 0)
			(layers "F.Cu" "F.Mask" "F.Paste")
			(net "GND")
		)
	)
	(footprint ""
		(layer "F.Cu")
		(at 20.11426 -164.737796)
		(property "Reference" "C1336"
			(at 0 0 0)
			(layer "F.SilkS")
			(hide yes)
			(effects
				(font
					(size 1.27 1.27)
				)
			)
		)
		(property "Value" ""
			(at 0 0 0)
			(layer "F.Fab")
			(effects
				(font
					(size 1.27 1.27)
				)
			)
		)
		(duplicate_pad_numbers_are_jumpers no)
		(fp_line
			(start -0.7874 -0.4064)
			(end 0.7874 -0.4064)
			(stroke
				(width 0.1524)
				(type default)
			)
			(layer "F.SilkS")
		)
		(fp_line
			(start -0.7874 0.4064)
			(end -0.7874 -0.4064)
			(stroke
				(width 0.1524)
				(type default)
			)
			(layer "F.SilkS")
		)
		(fp_line
			(start 0.7874 -0.4064)
			(end 0.7874 0.4064)
			(stroke
				(width 0.1524)
				(type default)
			)
			(layer "F.SilkS")
		)
		(fp_line
			(start 0.7874 0.4064)
			(end -0.7874 0.4064)
			(stroke
				(width 0.1524)
				(type default)
			)
			(layer "F.SilkS")
		)
		(fp_line
			(start -0.67945 -0.305054)
			(end -0.12065 -0.305054)
			(stroke
				(width 0.1)
				(type default)
			)
			(layer "F.Fab")
		)
		(fp_line
			(start -0.67945 0.3048)
			(end -0.67945 -0.305054)
			(stroke
				(width 0.1)
				(type default)
			)
			(layer "F.Fab")
		)
		(fp_line
			(start -0.12065 -0.305054)
			(end -0.12065 -0.2794)
			(stroke
				(width 0.1)
				(type default)
			)
			(layer "F.Fab")
		)
		(fp_line
			(start -0.12065 -0.2794)
			(end 0.12065 -0.2794)
			(stroke
				(width 0.1)
				(type default)
			)
			(layer "F.Fab")
		)
		(fp_line
			(start -0.12065 0.2794)
			(end -0.12065 0.3048)
			(stroke
				(width 0.1)
				(type default)
			)
			(layer "F.Fab")
		)
		(fp_line
			(start -0.12065 0.3048)
			(end -0.67945 0.3048)
			(stroke
				(width 0.1)
				(type default)
			)
			(layer "F.Fab")
		)
		(fp_line
			(start 0.120396 0.2794)
			(end -0.12065 0.2794)
			(stroke
				(width 0.1)
				(type default)
			)
			(layer "F.Fab")
		)
		(fp_line
			(start 0.120396 0.3048)
			(end 0.120396 0.2794)
			(stroke
				(width 0.1)
				(type default)
			)
			(layer "F.Fab")
		)
		(fp_line
			(start 0.12065 -0.3048)
			(end 0.67945 -0.3048)
			(stroke
				(width 0.1)
				(type default)
			)
			(layer "F.Fab")
		)
		(fp_line
			(start 0.12065 -0.2794)
			(end 0.12065 -0.3048)
			(stroke
				(width 0.1)
				(type default)
			)
			(layer "F.Fab")
		)
		(fp_line
			(start 0.67945 -0.3048)
			(end 0.67945 0.3048)
			(stroke
				(width 0.1)
				(type default)
			)
			(layer "F.Fab")
		)
		(fp_line
			(start 0.67945 0.3048)
			(end 0.120396 0.3048)
			(stroke
				(width 0.1)
				(type default)
			)
			(layer "F.Fab")
		)
		(pad "1" smd circle
			(at -0.40005 0)
			(size 0 0)
			(layers "F.Cu" "F.Mask" "F.Paste")
			(net "PVNN_TERM_CPU1")
		)
		(pad "2" smd circle
			(at 0.40005 0)
			(size 0 0)
			(layers "F.Cu" "F.Mask" "F.Paste")
			(net "GND")
		)
	)
)
